# S9S_MB_2U (Grand Teton) — schematic parts with pin connectivity, parts 1617–1617 of 6093; source: Cadence DE-HDL packaged netlist (pstxprt.dat, pstxnet.dat, pstchip.dat)

J24  SCONN288_ADR50017P087CC  SCONN288_ADR50017-P087CC IO  pkg DDR288S_1-1VXB  page 105
  1  VIN_BULK0  POWER  = P12V_S3_AUX_CPU1_NVDIMM
  2  RFU0  TRI  = TP_CHD_CPU1_DIMM2_FRU_0
  3  VIN_MGMT  POWER  = P3V3_AUX
  4  HSCL  IN  = I3C_SPD_DDRABCD_CPU1_LVC1_SCL_7
  5  HSDA  BI  = I3C_SPD_DDRABCD_CPU1_LVC1_SDA
  6  VSS0  POWER  = GND
  7  DQ0_A  BI  = M_D_CPU1_SA_DQ<0>
  8  VSS1  POWER  = GND
  9  DQ1_A  BI  = M_D_CPU1_SA_DQ<1>
  10  VSS2  POWER  = GND
  11  DQS0_A_T  BI  = M_D_CPU1_SA_DQS_DP<0>
  12  DQS0_A_C  BI  = M_D_CPU1_SA_DQS_DN<0>
  13  VSS3  POWER  = GND
  14  DQ4_A  BI  = M_D_CPU1_SA_DQ<4>
  15  VSS4  POWER  = GND
  16  DQ5_A  BI  = M_D_CPU1_SA_DQ<5>
  17  VSS5  POWER  = GND
  18  DQ8_A  BI  = M_D_CPU1_SA_DQ<8>
  19  VSS6  POWER  = GND
  20  DQ9_A  BI  = M_D_CPU1_SA_DQ<9>
  21  VSS7  POWER  = GND
  22  DQS1_A_T  BI  = M_D_CPU1_SA_DQS_DP<1>
  23  DQS1_A_C  BI  = M_D_CPU1_SA_DQS_DN<1>
  24  VSS8  POWER  = GND
  25  DQ12_A  BI  = M_D_CPU1_SA_DQ<12>
  26  VSS9  POWER  = GND
  27  DQ13_A  BI  = M_D_CPU1_SA_DQ<13>
  28  VSS10  POWER  = GND
  29  DQ16_A  BI  = M_D_CPU1_SA_DQ<16>
  30  VSS11  POWER  = GND
  31  DQ17_A  BI  = M_D_CPU1_SA_DQ<17>
  32  VSS12  POWER  = GND
  33  DQS2_A_T  BI  = M_D_CPU1_SA_DQS_DP<2>
  34  DQS2_A_C  BI  = M_D_CPU1_SA_DQS_DN<2>
  35  VSS13  POWER  = GND
  36  DQ20_A  BI  = M_D_CPU1_SA_DQ<20>
  37  VSS14  POWER  = GND
  38  DQ21_A  BI  = M_D_CPU1_SA_DQ<21>
  39  VSS15  POWER  = GND
  40  DQ24_A  BI  = M_D_CPU1_SA_DQ<24>
  41  VSS16  POWER  = GND
  42  DQ25_A  BI  = M_D_CPU1_SA_DQ<25>
  43  VSS17  POWER  = GND
  44  DQS3_A_T  BI  = M_D_CPU1_SA_DQS_DP<3>
  45  DQS3_A_C  BI  = M_D_CPU1_SA_DQS_DN<3>
  46  VSS18  POWER  = GND
  47  DQ28_A  BI  = M_D_CPU1_SA_DQ<28>
  48  VSS19  POWER  = GND
  49  DQ29_A  BI  = M_D_CPU1_SA_DQ<29>
  50  VSS20  POWER  = GND
  51  CB0_A  BI  = M_D_CPU1_SA_CB<0>
  52  VSS21  POWER  = GND
  53  CB1_A  BI  = M_D_CPU1_SA_CB<1>
  54  VSS22  POWER  = GND
  55  DQS4_A_T  BI  = M_D_CPU1_SA_DQS_DP<4>
  56  DQS4_A_C  BI  = M_D_CPU1_SA_DQS_DN<4>
  57  VSS23  POWER  = GND
  58  CB4_A  BI  = M_D_CPU1_SA_CB<4>
  59  VSS24  POWER  = GND
  60  CB5_A  BI  = M_D_CPU1_SA_CB<5>
  61  VSS25  POWER  = GND
  62  ALERT_N  OUT  = M_D_CPU1_ALERT_N
  63  VSS26  POWER  = GND
  64  CS0_A_N  IN  = M_D_CPU1_SA_CS_N<2>
  65  VSS27  POWER  = GND
  66  CA0_A  IN  = M_D_CPU1_SA_CA<0>
  67  VSS28  POWER  = GND
  68  CA2_A  IN  = M_D_CPU1_SA_CA<2>
  69  VSS29  POWER  = GND
  70  CA4_A  IN  = M_D_CPU1_SA_CA<4>
  71  VSS30  POWER  = GND
  72  CA6_A  IN  = M_D_CPU1_SA_CA<6>
  73  VSS31  POWER  = GND
  74  PAR_A  IN  = M_D_CPU1_SA_PAR
  75  VSS32  POWER  = GND
  76  CA0_B  IN  = M_D_CPU1_SB_CA<0>
  77  VSS33  POWER  = GND
  78  CA2_B  IN  = M_D_CPU1_SB_CA<2>
  79  VSS34  POWER  = GND
  80  CA4_B  IN  = M_D_CPU1_SB_CA<4>
  81  VSS35  POWER  = GND
  82  CA6_B  IN  = M_D_CPU1_SB_CA<6>
  83  VSS36  POWER  = GND
  84  CS0_B_N  IN  = M_D_CPU1_SB_CS_N<2>
  85  VSS37  POWER  = GND
  86  \lbd||rsp_a_n\  OUT  = M_D_CPU1_SA_RSP<1>
  87  \lbs||rsp_b_n\  OUT  = M_D_CPU1_SB_RSP<1>
  88  VSS38  POWER  = GND
  89  CB4_B  BI  = M_D_CPU1_SB_CB<4>
  90  VSS39  POWER  = GND
  91  CB5_B  BI  = M_D_CPU1_SB_CB<5>
  92  VSS40  POWER  = GND
  93  \dqs9_b_t||tdqs9_b_t||dbi4_b_n\  BI  = M_D_CPU1_SB_DQS_DP<9>
  94  \dqs9_b_c||tdqs9_b_c\  BI  = M_D_CPU1_SB_DQS_DN<9>
  95  VSS41  POWER  = GND
  96  CB0_B  BI  = M_D_CPU1_SB_CB<0>
  97  VSS42  POWER  = GND
  98  CB1_B  BI  = M_D_CPU1_SB_CB<1>
  99  VSS43  POWER  = GND
  100  DQ0_B  BI  = M_D_CPU1_SB_DQ<0>
  101  VSS44  POWER  = GND
  102  DQ1_B  BI  = M_D_CPU1_SB_DQ<1>
  103  VSS45  POWER  = GND
  104  DQS0_B_T  BI  = M_D_CPU1_SB_DQS_DP<0>
  105  DQS0_B_C  BI  = M_D_CPU1_SB_DQS_DN<0>
  106  VSS46  POWER  = GND
  107  DQ4_B  BI  = M_D_CPU1_SB_DQ<4>
  108  VSS47  POWER  = GND
  109  DQ5_B  BI  = M_D_CPU1_SB_DQ<5>
  110  VSS48  POWER  = GND
  111  DQ8_B  BI  = M_D_CPU1_SB_DQ<8>
  112  VSS49  POWER  = GND
  113  DQ9_B  BI  = M_D_CPU1_SB_DQ<9>
  114  VSS50  POWER  = GND
  115  DQS1_B_T  BI  = M_D_CPU1_SB_DQS_DP<1>
  116  DQS1_B_C  BI  = M_D_CPU1_SB_DQS_DN<1>
  117  VSS51  POWER  = GND
  118  DQ12_B  BI  = M_D_CPU1_SB_DQ<12>
  119  VSS52  POWER  = GND
  120  DQ13_B  BI  = M_D_CPU1_SB_DQ<13>
  121  VSS53  POWER  = GND
  122  DQ16_B  BI  = M_D_CPU1_SB_DQ<16>
  123  VSS54  POWER  = GND
  124  DQ17_B  BI  = M_D_CPU1_SB_DQ<17>
  125  VSS55  POWER  = GND
  126  DQS2_B_T  BI  = M_D_CPU1_SB_DQS_DP<2>
  127  DQS2_B_C  BI  = M_D_CPU1_SB_DQS_DN<2>
  128  VSS56  POWER  = GND
  129  DQ20_B  BI  = M_D_CPU1_SB_DQ<20>
  130  VSS57  POWER  = GND
  131  DQ21_B  BI  = M_D_CPU1_SB_DQ<21>
  132  VSS58  POWER  = GND
  133  DQ24_B  BI  = M_D_CPU1_SB_DQ<24>
  134  VSS59  POWER  = GND
  135  DQ25_B  BI  = M_D_CPU1_SB_DQ<25>
  136  VSS60  POWER  = GND
  137  DQS3_B_T  BI  = M_D_CPU1_SB_DQS_DP<3>
  138  DQS3_B_C  BI  = M_D_CPU1_SB_DQS_DN<3>
  139  VSS61  POWER  = GND
  140  DQ28_B  BI  = M_D_CPU1_SB_DQ<28>
  141  VSS62  POWER  = GND
  142  DQ29_B  BI  = M_D_CPU1_SB_DQ<29>
  143  VSS63  POWER  = GND
  144  RFU1  TRI  = TP_CHD_CPU1_DIMM2_FRU_1
  145  VIN_BULK1  POWER  = P12V_S3_AUX_CPU1_NVDIMM
  146  VIN_BULK2  POWER  = P12V_S3_AUX_CPU1_NVDIMM
  147  \pwr_good||fail_n\  BI  = PWRGD_CHD_CPU1_DIMM2
  148  HSA  IN  = PD_CHD_CPU1_DIMM2_SAA
  149  RFU2  TRI  = TP_CHD_CPU1_DIMM2_FRU_2
  150  RFU3  TRI  = TP_CHD_CPU1_DIMM2_FRU_3
  151  VSS64  POWER  = GND
  152  DQ2_A  BI  = M_D_CPU1_SA_DQ<2>
  153  VSS65  POWER  = GND
  154  DQ3_A  BI  = M_D_CPU1_SA_DQ<3>
  155  VSS66  POWER  = GND
  156  \dqs5_a_c||tdqs5_a_c||dqs5_a_t||tdqs5_a_t\  BI  = M_D_CPU1_SA_DQS_DN<5>
  157  \dqs5_a_t||tdqs5_a_t\  BI  = M_D_CPU1_SA_DQS_DP<5>
  158  VSS67  POWER  = GND
  159  DQ6_A  BI  = M_D_CPU1_SA_DQ<6>
  160  VSS68  POWER  = GND
  161  DQ7_A  BI  = M_D_CPU1_SA_DQ<7>
  162  VSS69  POWER  = GND
  163  DQ10_A  BI  = M_D_CPU1_SA_DQ<10>
  164  VSS70  POWER  = GND
  165  DQ11_A  BI  = M_D_CPU1_SA_DQ<11>
  166  VSS71  POWER  = GND
  167  \dqs6_a_c||tdqs6_a_c||dqs6_a_t||tdqs6_a_t\  BI  = M_D_CPU1_SA_DQS_DN<6>
  168  \dqs6_a_t||tdqs6_a_t\  BI  = M_D_CPU1_SA_DQS_DP<6>
  169  VSS72  POWER  = GND
  170  DQ14_A  BI  = M_D_CPU1_SA_DQ<14>
  171  VSS73  POWER  = GND
  172  DQ15_A  BI  = M_D_CPU1_SA_DQ<15>
  173  VSS74  POWER  = GND
  174  DQ18_A  BI  = M_D_CPU1_SA_DQ<18>
  175  VSS75  POWER  = GND
  176  DQ19_A  BI  = M_D_CPU1_SA_DQ<19>
  177  VSS76  POWER  = GND
  178  \dqs7_a_c||tdqs7_a_c\  BI  = M_D_CPU1_SA_DQS_DN<7>
  179  \dqs7_a_t||tdqs7_a_t\  BI  = M_D_CPU1_SA_DQS_DP<7>
  180  VSS77  POWER  = GND
  181  DQ22_A  BI  = M_D_CPU1_SA_DQ<22>
  182  VSS78  POWER  = GND
  183  DQ23_A  BI  = M_D_CPU1_SA_DQ<23>
  184  VSS79  POWER  = GND
  185  DQ26_A  BI  = M_D_CPU1_SA_DQ<26>
  186  VSS80  POWER  = GND
  187  DQ27_A  BI  = M_D_CPU1_SA_DQ<27>
  188  VSS81  POWER  = GND
  189  \dqs8_a_c||tdqs8_a_c\  BI  = M_D_CPU1_SA_DQS_DN<8>
  190  \dqs8_a_t||tdqs8_a_t\  BI  = M_D_CPU1_SA_DQS_DP<8>
  191  VSS82  POWER  = GND
  192  DQ30_A  BI  = M_D_CPU1_SA_DQ<30>
  193  VSS83  POWER  = GND
  194  DQ31_A  BI  = M_D_CPU1_SA_DQ<31>
  195  VSS84  POWER  = GND
  196  CB2_A  BI  = M_D_CPU1_SA_CB<2>
  197  VSS85  POWER  = GND
  198  CB3_A  BI  = M_D_CPU1_SA_CB<3>
  199  VSS86  POWER  = GND
  200  \dqs9_a_c||tdqs9_a_c\  BI  = M_D_CPU1_SA_DQS_DN<9>
  201  \dqs9_a_t||tdqs9_a_t\  BI  = M_D_CPU1_SA_DQS_DP<9>
  202  VSS87  POWER  = GND
  203  CB6_A  BI  = M_D_CPU1_SA_CB<6>
  204  VSS88  POWER  = GND
  205  CB7_A  BI  = M_D_CPU1_SA_CB<7>
  206  VSS89  POWER  = GND
  207  RESET_N  IN  = RST_M_CD_CPU1_FPGA_N
  208  VSS90  POWER  = GND
  209  CS1_A_N  IN  = M_D_CPU1_SA_CS_N<3>
  210  VSS91  POWER  = GND
  211  CA1_A  IN  = M_D_CPU1_SA_CA<1>
  212  VSS92  POWER  = GND
  213  CA3_A  IN  = M_D_CPU1_SA_CA<3>
  214  VSS93  POWER  = GND
  215  CA5_A  IN  = M_D_CPU1_SA_CA<5>
  216  VSS94  POWER  = GND
  217  CK_T  IN  = M_D_CPU1_CLK_DP<1>
  218  CK_C  IN  = M_D_CPU1_CLK_DN<1>
  219  VSS95  POWER  = GND
  220  RFU4  TRI  = TP_CHD_CPU1_DIMM2_FRU_4
  221  CA1_B  IN  = M_D_CPU1_SB_CA<1>
  222  VSS96  POWER  = GND
  223  CA3_B  IN  = M_D_CPU1_SB_CA<3>
  224  VSS97  POWER  = GND
  225  CA5_B  IN  = M_D_CPU1_SB_CA<5>
  226  VSS98  POWER  = GND
  227  PAR_B  IN  = M_D_CPU1_SB_PAR
  228  VSS99  POWER  = GND
  229  CS1_B_N  IN  = M_D_CPU1_SB_CS_N<3>
  230  VSS100  POWER  = GND
  231  RFU5  TRI  = TP_CHD_CPU1_DIMM2_FRU_5
  232  RFU6  TRI  = TP_CHD_CPU1_DIMM2_FRU_6
  233  VSS101  POWER  = GND
  234  CB6_B  BI  = M_D_CPU1_SB_CB<6>
  235  VSS102  POWER  = GND
  236  CB7_B  BI  = M_D_CPU1_SB_CB<7>
  237  VSS103  POWER  = GND
  238  DQS4_B_C  BI  = M_D_CPU1_SB_DQS_DN<4>
  239  DQS4_B_T  BI  = M_D_CPU1_SB_DQS_DP<4>
  240  VSS104  POWER  = GND
  241  CB2_B  BI  = M_D_CPU1_SB_CB<2>
  242  VSS105  POWER  = GND
  243  CB3_B  BI  = M_D_CPU1_SB_CB<3>
  244  VSS106  POWER  = GND
  245  DQ2_B  BI  = M_D_CPU1_SB_DQ<2>
  246  VSS107  POWER  = GND
  247  DQ3_B  BI  = M_D_CPU1_SB_DQ<3>
  248  VSS108  POWER  = GND
  249  \dqs5_b_c||tdqs5_b_c\  BI  = M_D_CPU1_SB_DQS_DN<5>
  250  \dqs5_b_t||tdqs5_b_t\  BI  = M_D_CPU1_SB_DQS_DP<5>
  251  VSS109  POWER  = GND
  252  DQ6_B  BI  = M_D_CPU1_SB_DQ<6>
  253  VSS110  POWER  = GND
  254  DQ7_B  BI  = M_D_CPU1_SB_DQ<7>
  255  VSS111  POWER  = GND
  256  DQ10_B  BI  = M_D_CPU1_SB_DQ<10>
  257  VSS112  POWER  = GND
  258  DQ11_B  BI  = M_D_CPU1_SB_DQ<11>
  259  VSS113  POWER  = GND
  260  \dqs6_b_c||tdqs6_b_c\  BI  = M_D_CPU1_SB_DQS_DN<6>
  261  \dqs6_b_t||tdqs6_b_t\  BI  = M_D_CPU1_SB_DQS_DP<6>
  262  VSS114  POWER  = GND
  263  DQ14_B  BI  = M_D_CPU1_SB_DQ<14>
  264  VSS115  POWER  = GND
  265  DQ15_B  BI  = M_D_CPU1_SB_DQ<15>
  266  VSS116  POWER  = GND
  267  DQ18_B  BI  = M_D_CPU1_SB_DQ<18>
  268  VSS117  POWER  = GND
  269  DQ19_B  BI  = M_D_CPU1_SB_DQ<19>
  270  VSS118  POWER  = GND
  271  \dqs7_b_c||tdqs7_b_c\  BI  = M_D_CPU1_SB_DQS_DN<7>
  272  \dqs7_b_t||tdqs7_b_t\  BI  = M_D_CPU1_SB_DQS_DP<7>
  273  VSS119  POWER  = GND
  274  DQ22_B  BI  = M_D_CPU1_SB_DQ<22>
  275  VSS120  POWER  = GND
  276  DQ23_B  BI  = M_D_CPU1_SB_DQ<23>
  277  VSS121  POWER  = GND
  278  DQ26_B  BI  = M_D_CPU1_SB_DQ<26>
  279  VSS122  POWER  = GND
  280  DQ27_B  BI  = M_D_CPU1_SB_DQ<27>
  281  VSS123  POWER  = GND
  282  \dqs8_b_c||tdqs8_b_c\  BI  = M_D_CPU1_SB_DQS_DN<8>
  283  \dqs8_b_t||tdqs8_b_t\  BI  = M_D_CPU1_SB_DQS_DP<8>
  284  VSS124  POWER  = GND
  285  DQ30_B  BI  = M_D_CPU1_SB_DQ<30>
  286  VSS125  POWER  = GND
  287  DQ31_B  BI  = M_D_CPU1_SB_DQ<31>
  288  VSS126  POWER  = GND
  G1  G1  POWER  = GND
  G2  G2  POWER  = GND
  G3  G3  POWER  = GND
